(kicad_pcb
	(version 20241229)
	(generator "pcbnew")
	(generator_version "9.0")
	(general
		(thickness 1.599998)
		(legacy_teardrops no)
	)
	(paper "A4")
	(title_block
		(title "Artix - Datacenter Secure Control Module (DC-SCM)")
		(date "2024-11-06")
		(rev "1.1.3")
		(comment 9 "footprints 383-387 of 544")
	)
	(layers
		(0 "F.Cu" signal)
		(4 "In1.Cu" signal)
		(6 "In2.Cu" signal)
		(8 "In3.Cu" signal)
		(10 "In4.Cu" signal)
		(12 "In5.Cu" signal)
		(14 "In6.Cu" signal)
		(2 "B.Cu" signal)
		(9 "F.Adhes" user "F.Adhesive")
		(11 "B.Adhes" user "B.Adhesive")
		(13 "F.Paste" user)
		(15 "B.Paste" user)
		(5 "F.SilkS" user "F.Silkscreen")
		(7 "B.SilkS" user "B.Silkscreen")
		(1 "F.Mask" user)
		(3 "B.Mask" user)
		(17 "Dwgs.User" user "User.Drawings")
		(19 "Cmts.User" user "User.Comments")
		(21 "Eco1.User" user "User.Eco1")
		(23 "Eco2.User" user "User.Eco2")
		(25 "Edge.Cuts" user)
		(27 "Margin" user)
		(31 "F.CrtYd" user "F.Courtyard")
		(29 "B.CrtYd" user "B.Courtyard")
		(35 "F.Fab" user)
		(33 "B.Fab" user)
	)
	(footprint "antmicro-footprints:C_0402_1005Metric"
		(layer "B.Cu")
		(at 122.335 129.665 -90)
		(descr "Capacitor SMD 0402")
		(tags "capacitor SMD 0402")
		(property "Reference" "C24"
			(at 0.835 -0.385 90)
			(layer "B.SilkS")
			(effects
				(font
					(size 0.7 0.7)
					(thickness 0.15)
				)
				(justify left bottom mirror)
			)
		)
		(property "Value" "C_100n_0402"
			(at 0 -1.4 90)
			(layer "B.Fab")
			(effects
				(font
					(size 0.7 0.7)
					(thickness 0.15)
				)
				(justify left bottom mirror)
			)
		)
		(property "Datasheet" "https://www.murata.com/products/productdetail?partno=GRM155R61H104KE14%23"
			(at 0 0 270)
			(layer "F.Fab")
			(hide yes)
			(effects
				(font
					(size 1.27 1.27)
					(thickness 0.15)
				)
			)
		)
		(property "Description" "SMD Multilayer Ceramic Capacitor, 0.1 µF, 50 V, 0402 [1005 Metric], ± 10%, X5R, GRM Series"
			(at 0 0 270)
			(layer "F.Fab")
			(hide yes)
			(effects
				(font
					(size 1.27 1.27)
					(thickness 0.15)
				)
			)
		)
		(property "Author" "Antmicro"
			(at -7.33 252 0)
			(layer "B.Fab")
			(hide yes)
			(effects
				(font
					(size 1 1)
					(thickness 0.15)
				)
				(justify mirror)
			)
		)
		(property "Dielectric" "X5R"
			(at -7.33 252 0)
			(layer "B.Fab")
			(hide yes)
			(effects
				(font
					(size 1 1)
					(thickness 0.15)
				)
				(justify mirror)
			)
		)
		(property "License" "Apache-2.0"
			(at -7.33 252 0)
			(layer "B.Fab")
			(hide yes)
			(effects
				(font
					(size 1 1)
					(thickness 0.15)
				)
				(justify mirror)
			)
		)
		(property "MPN" "GRM155R61H104KE14D"
			(at -7.33 252 0)
			(layer "B.Fab")
			(hide yes)
			(effects
				(font
					(size 1 1)
					(thickness 0.15)
				)
				(justify mirror)
			)
		)
		(property "Manufacturer" "Murata"
			(at -7.33 252 0)
			(layer "B.Fab")
			(hide yes)
			(effects
				(font
					(size 1 1)
					(thickness 0.15)
				)
				(justify mirror)
			)
		)
		(property "Val" "100n"
			(at -7.33 252 0)
			(layer "B.Fab")
			(hide yes)
			(effects
				(font
					(size 1 1)
					(thickness 0.15)
				)
				(justify mirror)
			)
		)
		(property "Voltage" "50V"
			(at -7.33 252 0)
			(layer "B.Fab")
			(hide yes)
			(effects
				(font
					(size 1 1)
					(thickness 0.15)
				)
				(justify mirror)
			)
		)
		(sheetname "/Interfaces/")
		(sheetfile "interfaces.kicad_sch")
		(attr smd)
		(fp_rect
			(start -0.925 0.47)
			(end 0.925 -0.47)
			(stroke
				(width 0.05)
				(type default)
			)
			(fill no)
			(layer "B.CrtYd")
		)
		(fp_line
			(start -0.494 0.25)
			(end 0.504 0.25)
			(stroke
				(width 0.15)
				(type solid)
			)
			(layer "B.Fab")
		)
		(fp_line
			(start 0.504 0.25)
			(end 0.504 -0.248)
			(stroke
				(width 0.15)
				(type solid)
			)
			(layer "B.Fab")
		)
		(fp_line
			(start -0.494 -0.248)
			(end -0.494 0.25)
			(stroke
				(width 0.15)
				(type solid)
			)
			(layer "B.Fab")
		)
		(fp_line
			(start 0.504 -0.248)
			(end -0.494 -0.248)
			(stroke
				(width 0.15)
				(type solid)
			)
			(layer "B.Fab")
		)
		(pad "1" smd roundrect
			(at -0.48 0 270)
			(size 0.59 0.64)
			(layers "B.Cu" "B.Mask" "B.Paste")
			(roundrect_rratio 0.25)
			(net 1 "GND")
			(pintype "passive")
		)
		(pad "2" smd roundrect
			(at 0.48 0 270)
			(size 0.59 0.64)
			(layers "B.Cu" "B.Mask" "B.Paste")
			(roundrect_rratio 0.25)
			(net 2 "VCC3V3")
			(pintype "passive")
		)
	)
	(footprint "antmicro-footprints:C_0402_1005Metric"
		(layer "B.Cu")
		(at 124.9075 113.475 -90)
		(descr "Capacitor SMD 0402")
		(tags "capacitor SMD 0402")
		(property "Reference" "C25"
			(at 0.825 -0.31375 90)
			(layer "B.SilkS")
			(effects
				(font
					(size 0.7 0.7)
					(thickness 0.15)
				)
				(justify left bottom mirror)
			)
		)
		(property "Value" "C_100n_0402"
			(at 0 -1.4 90)
			(layer "B.Fab")
			(effects
				(font
					(size 0.7 0.7)
					(thickness 0.15)
				)
				(justify left bottom mirror)
			)
		)
		(property "Datasheet" "https://www.murata.com/products/productdetail?partno=GRM155R61H104KE14%23"
			(at 0 0 270)
			(layer "F.Fab")
			(hide yes)
			(effects
				(font
					(size 1.27 1.27)
					(thickness 0.15)
				)
			)
		)
		(property "Description" "SMD Multilayer Ceramic Capacitor, 0.1 µF, 50 V, 0402 [1005 Metric], ± 10%, X5R, GRM Series"
			(at 0 0 270)
			(layer "F.Fab")
			(hide yes)
			(effects
				(font
					(size 1.27 1.27)
					(thickness 0.15)
				)
			)
		)
		(property "Author" "Antmicro"
			(at 11.4325 238.3825 0)
			(layer "B.Fab")
			(hide yes)
			(effects
				(font
					(size 1 1)
					(thickness 0.15)
				)
				(justify mirror)
			)
		)
		(property "Dielectric" "X5R"
			(at 11.4325 238.3825 0)
			(layer "B.Fab")
			(hide yes)
			(effects
				(font
					(size 1 1)
					(thickness 0.15)
				)
				(justify mirror)
			)
		)
		(property "License" "Apache-2.0"
			(at 11.4325 238.3825 0)
			(layer "B.Fab")
			(hide yes)
			(effects
				(font
					(size 1 1)
					(thickness 0.15)
				)
				(justify mirror)
			)
		)
		(property "MPN" "GRM155R61H104KE14D"
			(at 11.4325 238.3825 0)
			(layer "B.Fab")
			(hide yes)
			(effects
				(font
					(size 1 1)
					(thickness 0.15)
				)
				(justify mirror)
			)
		)
		(property "Manufacturer" "Murata"
			(at 11.4325 238.3825 0)
			(layer "B.Fab")
			(hide yes)
			(effects
				(font
					(size 1 1)
					(thickness 0.15)
				)
				(justify mirror)
			)
		)
		(property "Val" "100n"
			(at 11.4325 238.3825 0)
			(layer "B.Fab")
			(hide yes)
			(effects
				(font
					(size 1 1)
					(thickness 0.15)
				)
				(justify mirror)
			)
		)
		(property "Voltage" "50V"
			(at 11.4325 238.3825 0)
			(layer "B.Fab")
			(hide yes)
			(effects
				(font
					(size 1 1)
					(thickness 0.15)
				)
				(justify mirror)
			)
		)
		(sheetname "/Interfaces/")
		(sheetfile "interfaces.kicad_sch")
		(attr smd)
		(fp_rect
			(start -0.925 0.47)
			(end 0.925 -0.47)
			(stroke
				(width 0.05)
				(type default)
			)
			(fill no)
			(layer "B.CrtYd")
		)
		(fp_line
			(start -0.494 0.25)
			(end 0.504 0.25)
			(stroke
				(width 0.15)
				(type solid)
			)
			(layer "B.Fab")
		)
		(fp_line
			(start 0.504 0.25)
			(end 0.504 -0.248)
			(stroke
				(width 0.15)
				(type solid)
			)
			(layer "B.Fab")
		)
		(fp_line
			(start -0.494 -0.248)
			(end -0.494 0.25)
			(stroke
				(width 0.15)
				(type solid)
			)
			(layer "B.Fab")
		)
		(fp_line
			(start 0.504 -0.248)
			(end -0.494 -0.248)
			(stroke
				(width 0.15)
				(type solid)
			)
			(layer "B.Fab")
		)
		(pad "1" smd roundrect
			(at -0.48 0 270)
			(size 0.59 0.64)
			(layers "B.Cu" "B.Mask" "B.Paste")
			(roundrect_rratio 0.25)
			(net 1 "GND")
			(pintype "passive")
		)
		(pad "2" smd roundrect
			(at 0.48 0 270)
			(size 0.59 0.64)
			(layers "B.Cu" "B.Mask" "B.Paste")
			(roundrect_rratio 0.25)
			(net 12 "Net-(U17-VDDA1.8)")
			(pintype "passive")
		)
	)
	(footprint "antmicro-footprints:C_0402_1005Metric"
		(layer "B.Cu")
		(at 124 125.4 90)
		(descr "Capacitor SMD 0402")
		(tags "capacitor SMD 0402")
		(property "Reference" "C26"
			(at 0.8 0.4 90)
			(layer "B.SilkS")
			(effects
				(font
					(size 0.7 0.7)
					(thickness 0.15)
				)
				(justify right bottom mirror)
			)
		)
		(property "Value" "C_100n_0402"
			(at 0 -1.4 90)
			(layer "B.Fab")
			(effects
				(font
					(size 0.7 0.7)
					(thickness 0.15)
				)
				(justify right bottom mirror)
			)
		)
		(property "Datasheet" "https://www.murata.com/products/productdetail?partno=GRM155R61H104KE14%23"
			(at 0 0 90)
			(layer "F.Fab")
			(hide yes)
			(effects
				(font
					(size 1.27 1.27)
					(thickness 0.15)
				)
			)
		)
		(property "Description" "SMD Multilayer Ceramic Capacitor, 0.1 µF, 50 V, 0402 [1005 Metric], ± 10%, X5R, GRM Series"
			(at 0 0 90)
			(layer "F.Fab")
			(hide yes)
			(effects
				(font
					(size 1.27 1.27)
					(thickness 0.15)
				)
			)
		)
		(property "Author" "Antmicro"
			(at 249.4 1.4 0)
			(layer "B.Fab")
			(hide yes)
			(effects
				(font
					(size 1 1)
					(thickness 0.15)
				)
				(justify mirror)
			)
		)
		(property "Dielectric" "X5R"
			(at 249.4 1.4 0)
			(layer "B.Fab")
			(hide yes)
			(effects
				(font
					(size 1 1)
					(thickness 0.15)
				)
				(justify mirror)
			)
		)
		(property "License" "Apache-2.0"
			(at 249.4 1.4 0)
			(layer "B.Fab")
			(hide yes)
			(effects
				(font
					(size 1 1)
					(thickness 0.15)
				)
				(justify mirror)
			)
		)
		(property "MPN" "GRM155R61H104KE14D"
			(at 249.4 1.4 0)
			(layer "B.Fab")
			(hide yes)
			(effects
				(font
					(size 1 1)
					(thickness 0.15)
				)
				(justify mirror)
			)
		)
		(property "Manufacturer" "Murata"
			(at 249.4 1.4 0)
			(layer "B.Fab")
			(hide yes)
			(effects
				(font
					(size 1 1)
					(thickness 0.15)
				)
				(justify mirror)
			)
		)
		(property "Val" "100n"
			(at 249.4 1.4 0)
			(layer "B.Fab")
			(hide yes)
			(effects
				(font
					(size 1 1)
					(thickness 0.15)
				)
				(justify mirror)
			)
		)
		(property "Voltage" "50V"
			(at 249.4 1.4 0)
			(layer "B.Fab")
			(hide yes)
			(effects
				(font
					(size 1 1)
					(thickness 0.15)
				)
				(justify mirror)
			)
		)
		(sheetname "/Interfaces/")
		(sheetfile "interfaces.kicad_sch")
		(attr smd)
		(fp_rect
			(start -0.925 0.47)
			(end 0.925 -0.47)
			(stroke
				(width 0.05)
				(type default)
			)
			(fill no)
			(layer "B.CrtYd")
		)
		(fp_line
			(start 0.504 -0.248)
			(end -0.494 -0.248)
			(stroke
				(width 0.15)
				(type solid)
			)
			(layer "B.Fab")
		)
		(fp_line
			(start -0.494 -0.248)
			(end -0.494 0.25)
			(stroke
				(width 0.15)
				(type solid)
			)
			(layer "B.Fab")
		)
		(fp_line
			(start 0.504 0.25)
			(end 0.504 -0.248)
			(stroke
				(width 0.15)
				(type solid)
			)
			(layer "B.Fab")
		)
		(fp_line
			(start -0.494 0.25)
			(end 0.504 0.25)
			(stroke
				(width 0.15)
				(type solid)
			)
			(layer "B.Fab")
		)
		(pad "1" smd roundrect
			(at -0.48 0 90)
			(size 0.59 0.64)
			(layers "B.Cu" "B.Mask" "B.Paste")
			(roundrect_rratio 0.25)
			(net 1 "GND")
			(pintype "passive")
		)
		(pad "2" smd roundrect
			(at 0.48 0 90)
			(size 0.59 0.64)
			(layers "B.Cu" "B.Mask" "B.Paste")
			(roundrect_rratio 0.25)
			(net 108 "Net-(C177-Pad2)")
			(pintype "passive")
		)
	)
	(footprint "antmicro-footprints:C_0402_1005Metric"
		(layer "B.Cu")
		(at 100.2 98.12 -90)
		(descr "Capacitor SMD 0402")
		(tags "capacitor SMD 0402")
		(property "Reference" "C218"
			(at -3.62 -0.3 90)
			(layer "B.SilkS")
			(effects
				(font
					(size 0.7 0.7)
					(thickness 0.15)
				)
				(justify left bottom mirror)
			)
		)
		(property "Value" "C_10n_0402"
			(at 0 -1.4 90)
			(layer "B.Fab")
			(effects
				(font
					(size 0.7 0.7)
					(thickness 0.15)
				)
				(justify left bottom mirror)
			)
		)
		(property "Datasheet" "https://www.murata.com/products/productdetail?partno=GRM155R71H103KA88%23"
			(at 0 0 270)
			(layer "F.Fab")
			(hide yes)
			(effects
				(font
					(size 1.27 1.27)
					(thickness 0.15)
				)
			)
		)
		(property "Description" "SMD Multilayer Ceramic Capacitor, 10000 pF, 50 V, 0402 [1005 Metric], ± 10%, X7R, GRM Series"
			(at 0 0 270)
			(layer "F.Fab")
			(hide yes)
			(effects
				(font
					(size 1.27 1.27)
					(thickness 0.15)
				)
			)
		)
		(property "Author" "Antmicro"
			(at 2.08 198.32 0)
			(layer "B.Fab")
			(hide yes)
			(effects
				(font
					(size 1 1)
					(thickness 0.15)
				)
				(justify mirror)
			)
		)
		(property "Dielectric" "X7R"
			(at 2.08 198.32 0)
			(layer "B.Fab")
			(hide yes)
			(effects
				(font
					(size 1 1)
					(thickness 0.15)
				)
				(justify mirror)
			)
		)
		(property "License" "Apache-2.0"
			(at 2.08 198.32 0)
			(layer "B.Fab")
			(hide yes)
			(effects
				(font
					(size 1 1)
					(thickness 0.15)
				)
				(justify mirror)
			)
		)
		(property "MPN" "GRM155R71H103KA88D"
			(at 2.08 198.32 0)
			(layer "B.Fab")
			(hide yes)
			(effects
				(font
					(size 1 1)
					(thickness 0.15)
				)
				(justify mirror)
			)
		)
		(property "Manufacturer" "Murata"
			(at 2.08 198.32 0)
			(layer "B.Fab")
			(hide yes)
			(effects
				(font
					(size 1 1)
					(thickness 0.15)
				)
				(justify mirror)
			)
		)
		(property "Val" "10n"
			(at 2.08 198.32 0)
			(layer "B.Fab")
			(hide yes)
			(effects
				(font
					(size 1 1)
					(thickness 0.15)
				)
				(justify mirror)
			)
		)
		(property "Voltage" "50V"
			(at 2.08 198.32 0)
			(layer "B.Fab")
			(hide yes)
			(effects
				(font
					(size 1 1)
					(thickness 0.15)
				)
				(justify mirror)
			)
		)
		(sheetname "/Ethernet/")
		(sheetfile "ethernet.kicad_sch")
		(attr smd)
		(fp_rect
			(start -0.925 0.47)
			(end 0.925 -0.47)
			(stroke
				(width 0.05)
				(type default)
			)
			(fill no)
			(layer "B.CrtYd")
		)
		(fp_line
			(start -0.494 0.25)
			(end 0.504 0.25)
			(stroke
				(width 0.15)
				(type solid)
			)
			(layer "B.Fab")
		)
		(fp_line
			(start 0.504 0.25)
			(end 0.504 -0.248)
			(stroke
				(width 0.15)
				(type solid)
			)
			(layer "B.Fab")
		)
		(fp_line
			(start -0.494 -0.248)
			(end -0.494 0.25)
			(stroke
				(width 0.15)
				(type solid)
			)
			(layer "B.Fab")
		)
		(fp_line
			(start 0.504 -0.248)
			(end -0.494 -0.248)
			(stroke
				(width 0.15)
				(type solid)
			)
			(layer "B.Fab")
		)
		(pad "1" smd roundrect
			(at -0.48 0 270)
			(size 0.59 0.64)
			(layers "B.Cu" "B.Mask" "B.Paste")
			(roundrect_rratio 0.25)
			(net 1 "GND")
			(pintype "passive")
		)
		(pad "2" smd roundrect
			(at 0.48 0 270)
			(size 0.59 0.64)
			(layers "B.Cu" "B.Mask" "B.Paste")
			(roundrect_rratio 0.25)
			(net 339 "VCC1V2")
			(pintype "passive")
		)
	)
	(footprint "antmicro-footprints:C_0402_1005Metric"
		(layer "B.Cu")
		(at 125.395 129.665 -90)
		(descr "Capacitor SMD 0402")
		(tags "capacitor SMD 0402")
		(property "Reference" "C22"
			(at 0.835 -0.385 90)
			(layer "B.SilkS")
			(effects
				(font
					(size 0.7 0.7)
					(thickness 0.15)
				)
				(justify left bottom mirror)
			)
		)
		(property "Value" "C_100n_0402"
			(at 0 -1.4 90)
			(layer "B.Fab")
			(effects
				(font
					(size 0.7 0.7)
					(thickness 0.15)
				)
				(justify left bottom mirror)
			)
		)
		(property "Datasheet" "https://www.murata.com/products/productdetail?partno=GRM155R61H104KE14%23"
			(at 0 0 270)
			(layer "F.Fab")
			(hide yes)
			(effects
				(font
					(size 1.27 1.27)
					(thickness 0.15)
				)
			)
		)
		(property "Description" "SMD Multilayer Ceramic Capacitor, 0.1 µF, 50 V, 0402 [1005 Metric], ± 10%, X5R, GRM Series"
			(at 0 0 270)
			(layer "F.Fab")
			(hide yes)
			(effects
				(font
					(size 1.27 1.27)
					(thickness 0.15)
				)
			)
		)
		(property "Author" "Antmicro"
			(at -4.27 255.06 0)
			(layer "B.Fab")
			(hide yes)
			(effects
				(font
					(size 1 1)
					(thickness 0.15)
				)
				(justify mirror)
			)
		)
		(property "Dielectric" "X5R"
			(at -4.27 255.06 0)
			(layer "B.Fab")
			(hide yes)
			(effects
				(font
					(size 1 1)
					(thickness 0.15)
				)
				(justify mirror)
			)
		)
		(property "License" "Apache-2.0"
			(at -4.27 255.06 0)
			(layer "B.Fab")
			(hide yes)
			(effects
				(font
					(size 1 1)
					(thickness 0.15)
				)
				(justify mirror)
			)
		)
		(property "MPN" "GRM155R61H104KE14D"
			(at -4.27 255.06 0)
			(layer "B.Fab")
			(hide yes)
			(effects
				(font
					(size 1 1)
					(thickness 0.15)
				)
				(justify mirror)
			)
		)
		(property "Manufacturer" "Murata"
			(at -4.27 255.06 0)
			(layer "B.Fab")
			(hide yes)
			(effects
				(font
					(size 1 1)
					(thickness 0.15)
				)
				(justify mirror)
			)
		)
		(property "Val" "100n"
			(at -4.27 255.06 0)
			(layer "B.Fab")
			(hide yes)
			(effects
				(font
					(size 1 1)
					(thickness 0.15)
				)
				(justify mirror)
			)
		)
		(property "Voltage" "50V"
			(at -4.27 255.06 0)
			(layer "B.Fab")
			(hide yes)
			(effects
				(font
					(size 1 1)
					(thickness 0.15)
				)
				(justify mirror)
			)
		)
		(sheetname "/Interfaces/")
		(sheetfile "interfaces.kicad_sch")
		(attr smd)
		(fp_rect
			(start -0.925 0.47)
			(end 0.925 -0.47)
			(stroke
				(width 0.05)
				(type default)
			)
			(fill no)
			(layer "B.CrtYd")
		)
		(fp_line
			(start -0.494 0.25)
			(end 0.504 0.25)
			(stroke
				(width 0.15)
				(type solid)
			)
			(layer "B.Fab")
		)
		(fp_line
			(start 0.504 0.25)
			(end 0.504 -0.248)
			(stroke
				(width 0.15)
				(type solid)
			)
			(layer "B.Fab")
		)
		(fp_line
			(start -0.494 -0.248)
			(end -0.494 0.25)
			(stroke
				(width 0.15)
				(type solid)
			)
			(layer "B.Fab")
		)
		(fp_line
			(start 0.504 -0.248)
			(end -0.494 -0.248)
			(stroke
				(width 0.15)
				(type solid)
			)
			(layer "B.Fab")
		)
		(pad "1" smd roundrect
			(at -0.48 0 270)
			(size 0.59 0.64)
			(layers "B.Cu" "B.Mask" "B.Paste")
			(roundrect_rratio 0.25)
			(net 1 "GND")
			(pintype "passive")
		)
		(pad "2" smd roundrect
			(at 0.48 0 270)
			(size 0.59 0.64)
			(layers "B.Cu" "B.Mask" "B.Paste")
			(roundrect_rratio 0.25)
			(net 11 "Net-(U18-VDDA1.8)")
			(pintype "passive")
		)
	)
)
